(kicad_pcb
	(version 20260206)
	(generator "pcbnew")
	(generator_version "10.0")
	(general
		(thickness 1.6)
		(legacy_teardrops no)
	)
	(paper "A4")
	(title_block
		(title "04192023_DAF0TMB3IC0_F0TG_MB_C_brd_V02_OCP.brd")
		(comment 1 "Grand Teton / footprints 2774-2780 of 8354")
	)
	(layers
		(0 "F.Cu" signal "TOP")
		(4 "In1.Cu" signal "GND")
		(6 "In2.Cu" signal "IN1")
		(8 "In3.Cu" signal "GND1")
		(10 "In4.Cu" signal "IN2")
		(12 "In5.Cu" signal "GND2")
		(14 "In6.Cu" signal "IN3")
		(16 "In7.Cu" signal "GND3")
		(18 "In8.Cu" signal "VCC")
		(20 "In9.Cu" signal "VCC1")
		(22 "In10.Cu" signal "GND4")
		(24 "In11.Cu" signal "IN4")
		(26 "In12.Cu" signal "GND5")
		(28 "In13.Cu" signal "IN5")
		(30 "In14.Cu" signal "GND6")
		(32 "In15.Cu" signal "IN6")
		(34 "In16.Cu" signal "GND7")
		(2 "B.Cu" signal "BOTTOM")
		(9 "F.Adhes" user "F.Adhesive")
		(11 "B.Adhes" user "B.Adhesive")
		(13 "F.Paste" user "Package Geometry/Pastemask Top")
		(15 "B.Paste" user "Package Geometry/Pastemask Bottom")
		(5 "F.SilkS" user "Ref Des/Silkscreen Top")
		(7 "B.SilkS" user "Ref Des/Silkscreen Bottom")
		(1 "F.Mask" user "Board Geometry/Soldermask Top")
		(3 "B.Mask" user "Board Geometry/Soldermask Bottom")
		(17 "Dwgs.User" user "User.Drawings")
		(19 "Cmts.User" user "User.Comments")
		(21 "Eco1.User" user "User.Eco1")
		(23 "Eco2.User" user "User.Eco2")
		(25 "Edge.Cuts" user "Board Geometry/Outline")
		(27 "Margin" user)
		(31 "F.CrtYd" user "Package Geometry/Place Bound Top")
		(29 "B.CrtYd" user "Package Geometry/Place Bound Bottom")
		(35 "F.Fab" user "Ref Des/Assembly Top")
		(33 "B.Fab" user "Ref Des/Assembly Bottom")
	)
	(footprint ""
		(layer "F.Cu")
		(at 254.35433 -55.860442 -90)
		(property "Reference" "R3948"
			(at 0 0 270)
			(layer "F.SilkS")
			(hide yes)
			(effects
				(font
					(size 1.27 1.27)
				)
			)
		)
		(property "Value" ""
			(at 0 0 270)
			(layer "F.Fab")
			(effects
				(font
					(size 1.27 1.27)
				)
			)
		)
		(duplicate_pad_numbers_are_jumpers no)
		(fp_line
			(start -0.7874 0.4064)
			(end -0.7874 -0.4064)
			(stroke
				(width 0.1524)
				(type default)
			)
			(layer "F.SilkS")
		)
		(fp_line
			(start 0.7874 0.4064)
			(end -0.7874 0.4064)
			(stroke
				(width 0.1524)
				(type default)
			)
			(layer "F.SilkS")
		)
		(fp_line
			(start -0.7874 -0.4064)
			(end 0.7874 -0.4064)
			(stroke
				(width 0.1524)
				(type default)
			)
			(layer "F.SilkS")
		)
		(fp_line
			(start 0.7874 -0.4064)
			(end 0.7874 0.4064)
			(stroke
				(width 0.1524)
				(type default)
			)
			(layer "F.SilkS")
		)
		(fp_line
			(start -0.67945 0.3048)
			(end -0.67945 -0.305054)
			(stroke
				(width 0.1)
				(type default)
			)
			(layer "F.Fab")
		)
		(fp_line
			(start -0.12065 0.3048)
			(end -0.67945 0.3048)
			(stroke
				(width 0.1)
				(type default)
			)
			(layer "F.Fab")
		)
		(fp_line
			(start 0.120396 0.3048)
			(end 0.120396 0.2794)
			(stroke
				(width 0.1)
				(type default)
			)
			(layer "F.Fab")
		)
		(fp_line
			(start 0.67945 0.3048)
			(end 0.120396 0.3048)
			(stroke
				(width 0.1)
				(type default)
			)
			(layer "F.Fab")
		)
		(fp_line
			(start -0.12065 0.2794)
			(end -0.12065 0.3048)
			(stroke
				(width 0.1)
				(type default)
			)
			(layer "F.Fab")
		)
		(fp_line
			(start 0.120396 0.2794)
			(end -0.12065 0.2794)
			(stroke
				(width 0.1)
				(type default)
			)
			(layer "F.Fab")
		)
		(fp_line
			(start -0.12065 -0.2794)
			(end 0.12065 -0.2794)
			(stroke
				(width 0.1)
				(type default)
			)
			(layer "F.Fab")
		)
		(fp_line
			(start 0.12065 -0.2794)
			(end 0.12065 -0.3048)
			(stroke
				(width 0.1)
				(type default)
			)
			(layer "F.Fab")
		)
		(fp_line
			(start 0.12065 -0.3048)
			(end 0.67945 -0.3048)
			(stroke
				(width 0.1)
				(type default)
			)
			(layer "F.Fab")
		)
		(fp_line
			(start 0.67945 -0.3048)
			(end 0.67945 0.3048)
			(stroke
				(width 0.1)
				(type default)
			)
			(layer "F.Fab")
		)
		(fp_line
			(start -0.67945 -0.305054)
			(end -0.12065 -0.305054)
			(stroke
				(width 0.1)
				(type default)
			)
			(layer "F.Fab")
		)
		(fp_line
			(start -0.12065 -0.305054)
			(end -0.12065 -0.2794)
			(stroke
				(width 0.1)
				(type default)
			)
			(layer "F.Fab")
		)
		(pad "1" smd circle
			(at -0.40005 0 270)
			(size 0 0)
			(layers "F.Cu" "F.Mask" "F.Paste")
			(net "P3V3_AUX")
		)
		(pad "2" smd circle
			(at 0.40005 0 270)
			(size 0 0)
			(layers "F.Cu" "F.Mask" "F.Paste")
			(net "HP_LVC3_E1S_0_HSC_PWRGD")
		)
	)
	(footprint ""
		(layer "F.Cu")
		(at 161.29 -356.362 90)
		(property "Reference" "R350"
			(at 0 0 90)
			(layer "F.SilkS")
			(hide yes)
			(effects
				(font
					(size 1.27 1.27)
				)
			)
		)
		(property "Value" ""
			(at 0 0 90)
			(layer "F.Fab")
			(effects
				(font
					(size 1.27 1.27)
				)
			)
		)
		(duplicate_pad_numbers_are_jumpers no)
		(fp_line
			(start 0.7874 -0.4064)
			(end 0.7874 0.4064)
			(stroke
				(width 0.1524)
				(type default)
			)
			(layer "F.SilkS")
		)
		(fp_line
			(start -0.7874 -0.4064)
			(end 0.7874 -0.4064)
			(stroke
				(width 0.1524)
				(type default)
			)
			(layer "F.SilkS")
		)
		(fp_line
			(start 0.7874 0.4064)
			(end -0.7874 0.4064)
			(stroke
				(width 0.1524)
				(type default)
			)
			(layer "F.SilkS")
		)
		(fp_line
			(start -0.7874 0.4064)
			(end -0.7874 -0.4064)
			(stroke
				(width 0.1524)
				(type default)
			)
			(layer "F.SilkS")
		)
		(fp_line
			(start -0.12065 -0.305054)
			(end -0.12065 -0.2794)
			(stroke
				(width 0.1)
				(type default)
			)
			(layer "F.Fab")
		)
		(fp_line
			(start -0.67945 -0.305054)
			(end -0.12065 -0.305054)
			(stroke
				(width 0.1)
				(type default)
			)
			(layer "F.Fab")
		)
		(fp_line
			(start 0.67945 -0.3048)
			(end 0.67945 0.3048)
			(stroke
				(width 0.1)
				(type default)
			)
			(layer "F.Fab")
		)
		(fp_line
			(start 0.12065 -0.3048)
			(end 0.67945 -0.3048)
			(stroke
				(width 0.1)
				(type default)
			)
			(layer "F.Fab")
		)
		(fp_line
			(start 0.12065 -0.2794)
			(end 0.12065 -0.3048)
			(stroke
				(width 0.1)
				(type default)
			)
			(layer "F.Fab")
		)
		(fp_line
			(start -0.12065 -0.2794)
			(end 0.12065 -0.2794)
			(stroke
				(width 0.1)
				(type default)
			)
			(layer "F.Fab")
		)
		(fp_line
			(start 0.120396 0.2794)
			(end -0.12065 0.2794)
			(stroke
				(width 0.1)
				(type default)
			)
			(layer "F.Fab")
		)
		(fp_line
			(start -0.12065 0.2794)
			(end -0.12065 0.3048)
			(stroke
				(width 0.1)
				(type default)
			)
			(layer "F.Fab")
		)
		(fp_line
			(start 0.67945 0.3048)
			(end 0.120396 0.3048)
			(stroke
				(width 0.1)
				(type default)
			)
			(layer "F.Fab")
		)
		(fp_line
			(start 0.120396 0.3048)
			(end 0.120396 0.2794)
			(stroke
				(width 0.1)
				(type default)
			)
			(layer "F.Fab")
		)
		(fp_line
			(start -0.12065 0.3048)
			(end -0.67945 0.3048)
			(stroke
				(width 0.1)
				(type default)
			)
			(layer "F.Fab")
		)
		(fp_line
			(start -0.67945 0.3048)
			(end -0.67945 -0.305054)
			(stroke
				(width 0.1)
				(type default)
			)
			(layer "F.Fab")
		)
		(pad "1" smd circle
			(at -0.40005 0 90)
			(size 0 0)
			(layers "F.Cu" "F.Mask" "F.Paste")
			(net "SMB_SCM_2_R2_SDA")
		)
		(pad "2" smd circle
			(at 0.40005 0 90)
			(size 0 0)
			(layers "F.Cu" "F.Mask" "F.Paste")
			(net "SMB_SCM_2_R5_SDA")
		)
	)
	(footprint ""
		(layer "F.Cu")
		(at 12.954 -79.0194)
		(property "Reference" "U58"
			(at -1.4732 -1.768348 0)
			(unlocked yes)
			(layer "F.SilkS")
			(effects
				(font
					(size 0.7874 0.5842)
					(thickness 0.1524)
				)
				(justify left)
			)
		)
		(property "Value" ""
			(at 0 0 0)
			(layer "F.Fab")
			(effects
				(font
					(size 1.27 1.27)
				)
			)
		)
		(duplicate_pad_numbers_are_jumpers no)
		(fp_line
			(start -1.38176 -1.100074)
			(end -1.38176 1.100074)
			(stroke
				(width 0.1524)
				(type default)
			)
			(layer "F.SilkS")
		)
		(fp_line
			(start -1.38176 1.100074)
			(end 1.38176 1.100074)
			(stroke
				(width 0.1524)
				(type default)
			)
			(layer "F.SilkS")
		)
		(fp_line
			(start -0.592074 -1.100074)
			(end -1.38176 -1.100074)
			(stroke
				(width 0.1524)
				(type default)
			)
			(layer "F.SilkS")
		)
		(fp_line
			(start 0 -0.508)
			(end -0.592074 -1.100074)
			(stroke
				(width 0.1524)
				(type default)
			)
			(layer "F.SilkS")
		)
		(fp_line
			(start 0.592074 -1.100074)
			(end 0 -0.508)
			(stroke
				(width 0.1524)
				(type default)
			)
			(layer "F.SilkS")
		)
		(fp_line
			(start 1.38176 -1.100074)
			(end 0.592074 -1.100074)
			(stroke
				(width 0.1524)
				(type default)
			)
			(layer "F.SilkS")
		)
		(fp_line
			(start 1.38176 1.100074)
			(end 1.38176 -1.100074)
			(stroke
				(width 0.1524)
				(type default)
			)
			(layer "F.SilkS")
		)
		(fp_poly
			(pts
				(xy -1.896618 -0.424688) (xy -1.896618 -0.865124) (xy -1.455928 -0.644906)
			)
			(stroke
				(width 0)
				(type default)
			)
			(fill yes)
			(layer "F.SilkS")
		)
		(fp_line
			(start -0.674878 -1.100074)
			(end -0.674878 1.100074)
			(stroke
				(width 0.1)
				(type default)
			)
			(layer "F.Fab")
		)
		(fp_line
			(start -0.674878 1.100074)
			(end 0.674878 1.100074)
			(stroke
				(width 0.1)
				(type default)
			)
			(layer "F.Fab")
		)
		(fp_line
			(start 0.674878 -1.100074)
			(end -0.674878 -1.100074)
			(stroke
				(width 0.1)
				(type default)
			)
			(layer "F.Fab")
		)
		(fp_line
			(start 0.674878 1.100074)
			(end 0.674878 -1.100074)
			(stroke
				(width 0.1)
				(type default)
			)
			(layer "F.Fab")
		)
		(fp_poly
			(pts
				(xy -1.9431 -0.870204) (xy -1.50241 -0.649986) (xy -1.9431 -0.429768)
			)
			(stroke
				(width 0)
				(type default)
			)
			(fill yes)
			(layer "F.Fab")
		)
		(pad "1" smd rect
			(at -0.94996 -0.649986 270)
			(size 0.4318 0.6096)
			(layers "F.Cu" "F.Mask" "F.Paste")
			(net "OCP_V3_2_PRSNT0_R_N")
		)
		(pad "2" smd rect
			(at -0.94996 0 270)
			(size 0.4318 0.6096)
			(layers "F.Cu" "F.Mask" "F.Paste")
			(net "GND")
		)
		(pad "3" smd rect
			(at -0.94996 0.649986 270)
			(size 0.4318 0.6096)
			(layers "F.Cu" "F.Mask" "F.Paste")
			(net "OCP_V3_2_PRSNT1_R_N")
		)
		(pad "4" smd rect
			(at 0.94996 0.649986 270)
			(size 0.4318 0.6096)
			(layers "F.Cu" "F.Mask" "F.Paste")
			(net "HP_LVC3_OCP_V3_2_PRSNT2_N_R")
		)
		(pad "5" smd rect
			(at 0.94996 0 270)
			(size 0.4318 0.6096)
			(layers "F.Cu" "F.Mask" "F.Paste")
			(net "P3V3_AUX")
		)
		(pad "6" smd rect
			(at 0.94996 -0.649986 270)
			(size 0.4318 0.6096)
			(layers "F.Cu" "F.Mask" "F.Paste")
			(net "HP_LVC3_OCP_V3_2_PRSNT2_N_R")
		)
	)
	(footprint ""
		(layer "F.Cu")
		(at 37.592 -359.664 90)
		(property "Reference" "PR246"
			(at 0 0 90)
			(layer "F.SilkS")
			(hide yes)
			(effects
				(font
					(size 1.27 1.27)
				)
			)
		)
		(property "Value" ""
			(at 0 0 90)
			(layer "F.Fab")
			(effects
				(font
					(size 1.27 1.27)
				)
			)
		)
		(duplicate_pad_numbers_are_jumpers no)
		(fp_line
			(start 0.7874 -0.4064)
			(end 0.7874 0.4064)
			(stroke
				(width 0.1524)
				(type default)
			)
			(layer "F.SilkS")
		)
		(fp_line
			(start -0.7874 -0.4064)
			(end 0.7874 -0.4064)
			(stroke
				(width 0.1524)
				(type default)
			)
			(layer "F.SilkS")
		)
		(fp_line
			(start 0.7874 0.4064)
			(end -0.7874 0.4064)
			(stroke
				(width 0.1524)
				(type default)
			)
			(layer "F.SilkS")
		)
		(fp_line
			(start -0.7874 0.4064)
			(end -0.7874 -0.4064)
			(stroke
				(width 0.1524)
				(type default)
			)
			(layer "F.SilkS")
		)
		(fp_line
			(start -0.12065 -0.305054)
			(end -0.12065 -0.2794)
			(stroke
				(width 0.1)
				(type default)
			)
			(layer "F.Fab")
		)
		(fp_line
			(start -0.67945 -0.305054)
			(end -0.12065 -0.305054)
			(stroke
				(width 0.1)
				(type default)
			)
			(layer "F.Fab")
		)
		(fp_line
			(start 0.67945 -0.3048)
			(end 0.67945 0.3048)
			(stroke
				(width 0.1)
				(type default)
			)
			(layer "F.Fab")
		)
		(fp_line
			(start 0.12065 -0.3048)
			(end 0.67945 -0.3048)
			(stroke
				(width 0.1)
				(type default)
			)
			(layer "F.Fab")
		)
		(fp_line
			(start 0.12065 -0.2794)
			(end 0.12065 -0.3048)
			(stroke
				(width 0.1)
				(type default)
			)
			(layer "F.Fab")
		)
		(fp_line
			(start -0.12065 -0.2794)
			(end 0.12065 -0.2794)
			(stroke
				(width 0.1)
				(type default)
			)
			(layer "F.Fab")
		)
		(fp_line
			(start 0.120396 0.2794)
			(end -0.12065 0.2794)
			(stroke
				(width 0.1)
				(type default)
			)
			(layer "F.Fab")
		)
		(fp_line
			(start -0.12065 0.2794)
			(end -0.12065 0.3048)
			(stroke
				(width 0.1)
				(type default)
			)
			(layer "F.Fab")
		)
		(fp_line
			(start 0.67945 0.3048)
			(end 0.120396 0.3048)
			(stroke
				(width 0.1)
				(type default)
			)
			(layer "F.Fab")
		)
		(fp_line
			(start 0.120396 0.3048)
			(end 0.120396 0.2794)
			(stroke
				(width 0.1)
				(type default)
			)
			(layer "F.Fab")
		)
		(fp_line
			(start -0.12065 0.3048)
			(end -0.67945 0.3048)
			(stroke
				(width 0.1)
				(type default)
			)
			(layer "F.Fab")
		)
		(fp_line
			(start -0.67945 0.3048)
			(end -0.67945 -0.305054)
			(stroke
				(width 0.1)
				(type default)
			)
			(layer "F.Fab")
		)
		(pad "1" smd circle
			(at -0.40005 0 90)
			(size 0 0)
			(layers "F.Cu" "F.Mask" "F.Paste")
			(net "VSENSE_PVDDIO_P1_DP")
		)
		(pad "2" smd circle
			(at 0.40005 0 90)
			(size 0 0)
			(layers "F.Cu" "F.Mask" "F.Paste")
			(net "VSENSE_PVDDIO_P1_VSEN1")
		)
	)
	(footprint ""
		(layer "F.Cu")
		(at 129.723896 -375.49963 -90)
		(property "Reference" "C1526"
			(at 0 0 270)
			(layer "F.SilkS")
			(hide yes)
			(effects
				(font
					(size 1.27 1.27)
				)
			)
		)
		(property "Value" ""
			(at 0 0 270)
			(layer "F.Fab")
			(effects
				(font
					(size 1.27 1.27)
				)
			)
		)
		(duplicate_pad_numbers_are_jumpers no)
		(fp_line
			(start -0.299974 0.150114)
			(end -0.299974 -0.150114)
			(stroke
				(width 0.1)
				(type default)
			)
			(layer "F.Fab")
		)
		(fp_line
			(start 0.299974 0.150114)
			(end -0.299974 0.150114)
			(stroke
				(width 0.1)
				(type default)
			)
			(layer "F.Fab")
		)
		(fp_line
			(start -0.299974 -0.150114)
			(end 0.299974 -0.150114)
			(stroke
				(width 0.1)
				(type default)
			)
			(layer "F.Fab")
		)
		(fp_line
			(start 0.299974 -0.150114)
			(end 0.299974 0.150114)
			(stroke
				(width 0.1)
				(type default)
			)
			(layer "F.Fab")
		)
		(pad "1" smd rect
			(at -0.2667 0 270)
			(size 0.3048 0.381)
			(layers "F.Cu" "F.Mask" "F.Paste")
			(net "P5E_CPU1_P3_TX_C_DN<10>")
		)
		(pad "2" smd rect
			(at 0.2667 0 270)
			(size 0.3048 0.381)
			(layers "F.Cu" "F.Mask" "F.Paste")
			(net "P5E_CPU1_P3_TX_DN<10>")
		)
	)
	(footprint ""
		(layer "F.Cu")
		(at 91.748102 -370.57203 -90)
		(property "Reference" "C722"
			(at 0 0 270)
			(layer "F.SilkS")
			(hide yes)
			(effects
				(font
					(size 1.27 1.27)
				)
			)
		)
		(property "Value" ""
			(at 0 0 270)
			(layer "F.Fab")
			(effects
				(font
					(size 1.27 1.27)
				)
			)
		)
		(duplicate_pad_numbers_are_jumpers no)
		(fp_line
			(start -0.299974 0.150114)
			(end -0.299974 -0.150114)
			(stroke
				(width 0.1)
				(type default)
			)
			(layer "F.Fab")
		)
		(fp_line
			(start 0.299974 0.150114)
			(end -0.299974 0.150114)
			(stroke
				(width 0.1)
				(type default)
			)
			(layer "F.Fab")
		)
		(fp_line
			(start -0.299974 -0.150114)
			(end 0.299974 -0.150114)
			(stroke
				(width 0.1)
				(type default)
			)
			(layer "F.Fab")
		)
		(fp_line
			(start 0.299974 -0.150114)
			(end 0.299974 0.150114)
			(stroke
				(width 0.1)
				(type default)
			)
			(layer "F.Fab")
		)
		(pad "1" smd rect
			(at -0.2667 0 270)
			(size 0.3048 0.381)
			(layers "F.Cu" "F.Mask" "F.Paste")
			(net "P5E_CPU1_P1_TX_C_DN<9>")
		)
		(pad "2" smd rect
			(at 0.2667 0 270)
			(size 0.3048 0.381)
			(layers "F.Cu" "F.Mask" "F.Paste")
			(net "P5E_CPU1_P1_TX_DN<9>")
		)
	)
	(footprint ""
		(layer "F.Cu")
		(at 250.55957 -67.254374 180)
		(property "Reference" "R4073"
			(at 0 0 180)
			(layer "F.SilkS")
			(hide yes)
			(effects
				(font
					(size 1.27 1.27)
				)
			)
		)
		(property "Value" ""
			(at 0 0 180)
			(layer "F.Fab")
			(effects
				(font
					(size 1.27 1.27)
				)
			)
		)
		(duplicate_pad_numbers_are_jumpers no)
		(fp_line
			(start 0.7874 0.4064)
			(end -0.7874 0.4064)
			(stroke
				(width 0.1524)
				(type default)
			)
			(layer "F.SilkS")
		)
		(fp_line
			(start 0.7874 -0.4064)
			(end 0.7874 0.4064)
			(stroke
				(width 0.1524)
				(type default)
			)
			(layer "F.SilkS")
		)
		(fp_line
			(start -0.7874 0.4064)
			(end -0.7874 -0.4064)
			(stroke
				(width 0.1524)
				(type default)
			)
			(layer "F.SilkS")
		)
		(fp_line
			(start -0.7874 -0.4064)
			(end 0.7874 -0.4064)
			(stroke
				(width 0.1524)
				(type default)
			)
			(layer "F.SilkS")
		)
		(fp_line
			(start 0.67945 0.3048)
			(end 0.120396 0.3048)
			(stroke
				(width 0.1)
				(type default)
			)
			(layer "F.Fab")
		)
		(fp_line
			(start 0.67945 -0.3048)
			(end 0.67945 0.3048)
			(stroke
				(width 0.1)
				(type default)
			)
			(layer "F.Fab")
		)
		(fp_line
			(start 0.12065 -0.2794)
			(end 0.12065 -0.3048)
			(stroke
				(width 0.1)
				(type default)
			)
			(layer "F.Fab")
		)
		(fp_line
			(start 0.12065 -0.3048)
			(end 0.67945 -0.3048)
			(stroke
				(width 0.1)
				(type default)
			)
			(layer "F.Fab")
		)
		(fp_line
			(start 0.120396 0.3048)
			(end 0.120396 0.2794)
			(stroke
				(width 0.1)
				(type default)
			)
			(layer "F.Fab")
		)
		(fp_line
			(start 0.120396 0.2794)
			(end -0.12065 0.2794)
			(stroke
				(width 0.1)
				(type default)
			)
			(layer "F.Fab")
		)
		(fp_line
			(start -0.12065 0.3048)
			(end -0.67945 0.3048)
			(stroke
				(width 0.1)
				(type default)
			)
			(layer "F.Fab")
		)
		(fp_line
			(start -0.12065 0.2794)
			(end -0.12065 0.3048)
			(stroke
				(width 0.1)
				(type default)
			)
			(layer "F.Fab")
		)
		(fp_line
			(start -0.12065 -0.2794)
			(end 0.12065 -0.2794)
			(stroke
				(width 0.1)
				(type default)
			)
			(layer "F.Fab")
		)
		(fp_line
			(start -0.12065 -0.305054)
			(end -0.12065 -0.2794)
			(stroke
				(width 0.1)
				(type default)
			)
			(layer "F.Fab")
		)
		(fp_line
			(start -0.67945 0.3048)
			(end -0.67945 -0.305054)
			(stroke
				(width 0.1)
				(type default)
			)
			(layer "F.Fab")
		)
		(fp_line
			(start -0.67945 -0.305054)
			(end -0.12065 -0.305054)
			(stroke
				(width 0.1)
				(type default)
			)
			(layer "F.Fab")
		)
		(pad "1" smd circle
			(at -0.40005 0 180)
			(size 0 0)
			(layers "F.Cu" "F.Mask" "F.Paste")
			(net "P12V_E1S_EN_0_R")
		)
		(pad "2" smd circle
			(at 0.40005 0 180)
			(size 0 0)
			(layers "F.Cu" "F.Mask" "F.Paste")
			(net "GND")
		)
	)
)
